(kicad_pcb
	(version 20260206)
	(generator "pcbnew")
	(generator_version "10.0")
	(general
		(thickness 1.6)
		(legacy_teardrops no)
	)
	(paper "A4")
	(title_block
		(title "01162023_DA0F0TEBIF0_F0T_Expander_BD_F_brd_V02_OCP.brd")
		(comment 1 "Grand Teton / footprints 3877-3883 of 9728")
	)
	(layers
		(0 "F.Cu" signal "TOP")
		(4 "In1.Cu" signal "GND")
		(6 "In2.Cu" signal "VCC")
		(8 "In3.Cu" signal "VCC1")
		(10 "In4.Cu" signal "GND1")
		(12 "In5.Cu" signal "IN1")
		(14 "In6.Cu" signal "GND2")
		(16 "In7.Cu" signal "IN2")
		(18 "In8.Cu" signal "GND3")
		(20 "In9.Cu" signal "IN3")
		(22 "In10.Cu" signal "GND4")
		(24 "In11.Cu" signal "IN4")
		(26 "In12.Cu" signal "GND5")
		(28 "In13.Cu" signal "IN5")
		(30 "In14.Cu" signal "GND6")
		(32 "In15.Cu" signal "IN6")
		(34 "In16.Cu" signal "GND7")
		(2 "B.Cu" signal "BOTTOM")
		(9 "F.Adhes" user "F.Adhesive")
		(11 "B.Adhes" user "B.Adhesive")
		(13 "F.Paste" user "Package Geometry/Pastemask Top")
		(15 "B.Paste" user "Package Geometry/Pastemask Bottom")
		(5 "F.SilkS" user "Ref Des/Silkscreen Top")
		(7 "B.SilkS" user "Ref Des/Silkscreen Bottom")
		(1 "F.Mask" user "Board Geometry/Soldermask Top")
		(3 "B.Mask" user "Board Geometry/Soldermask Bottom")
		(17 "Dwgs.User" user "User.Drawings")
		(19 "Cmts.User" user "User.Comments")
		(21 "Eco1.User" user "User.Eco1")
		(23 "Eco2.User" user "User.Eco2")
		(25 "Edge.Cuts" user "Board Geometry/Outline")
		(27 "Margin" user)
		(31 "F.CrtYd" user "Package Geometry/Place Bound Top")
		(29 "B.CrtYd" user "Package Geometry/Place Bound Bottom")
		(35 "F.Fab" user "Ref Des/Assembly Top")
		(33 "B.Fab" user "Ref Des/Assembly Bottom")
	)
	(footprint ""
		(layer "F.Cu")
		(at 251.446792 -38.49116 180)
		(property "Reference" "R6089"
			(at 0 0 180)
			(layer "F.SilkS")
			(hide yes)
			(effects
				(font
					(size 1.27 1.27)
				)
			)
		)
		(property "Value" ""
			(at 0 0 180)
			(layer "F.Fab")
			(effects
				(font
					(size 1.27 1.27)
				)
			)
		)
		(duplicate_pad_numbers_are_jumpers no)
		(fp_line
			(start 0.7874 0.4064)
			(end -0.7874 0.4064)
			(stroke
				(width 0.1524)
				(type default)
			)
			(layer "F.SilkS")
		)
		(fp_line
			(start 0.7874 -0.4064)
			(end 0.7874 0.4064)
			(stroke
				(width 0.1524)
				(type default)
			)
			(layer "F.SilkS")
		)
		(fp_line
			(start -0.7874 0.4064)
			(end -0.7874 -0.4064)
			(stroke
				(width 0.1524)
				(type default)
			)
			(layer "F.SilkS")
		)
		(fp_line
			(start -0.7874 -0.4064)
			(end 0.7874 -0.4064)
			(stroke
				(width 0.1524)
				(type default)
			)
			(layer "F.SilkS")
		)
		(fp_line
			(start 0.67945 0.3048)
			(end 0.120396 0.3048)
			(stroke
				(width 0.1)
				(type default)
			)
			(layer "F.Fab")
		)
		(fp_line
			(start 0.67945 -0.3048)
			(end 0.67945 0.3048)
			(stroke
				(width 0.1)
				(type default)
			)
			(layer "F.Fab")
		)
		(fp_line
			(start 0.12065 -0.2794)
			(end 0.12065 -0.3048)
			(stroke
				(width 0.1)
				(type default)
			)
			(layer "F.Fab")
		)
		(fp_line
			(start 0.12065 -0.3048)
			(end 0.67945 -0.3048)
			(stroke
				(width 0.1)
				(type default)
			)
			(layer "F.Fab")
		)
		(fp_line
			(start 0.120396 0.3048)
			(end 0.120396 0.2794)
			(stroke
				(width 0.1)
				(type default)
			)
			(layer "F.Fab")
		)
		(fp_line
			(start 0.120396 0.2794)
			(end -0.12065 0.2794)
			(stroke
				(width 0.1)
				(type default)
			)
			(layer "F.Fab")
		)
		(fp_line
			(start -0.12065 0.3048)
			(end -0.67945 0.3048)
			(stroke
				(width 0.1)
				(type default)
			)
			(layer "F.Fab")
		)
		(fp_line
			(start -0.12065 0.2794)
			(end -0.12065 0.3048)
			(stroke
				(width 0.1)
				(type default)
			)
			(layer "F.Fab")
		)
		(fp_line
			(start -0.12065 -0.2794)
			(end 0.12065 -0.2794)
			(stroke
				(width 0.1)
				(type default)
			)
			(layer "F.Fab")
		)
		(fp_line
			(start -0.12065 -0.305054)
			(end -0.12065 -0.2794)
			(stroke
				(width 0.1)
				(type default)
			)
			(layer "F.Fab")
		)
		(fp_line
			(start -0.67945 0.3048)
			(end -0.67945 -0.305054)
			(stroke
				(width 0.1)
				(type default)
			)
			(layer "F.Fab")
		)
		(fp_line
			(start -0.67945 -0.305054)
			(end -0.12065 -0.305054)
			(stroke
				(width 0.1)
				(type default)
			)
			(layer "F.Fab")
		)
		(pad "1" smd circle
			(at -0.40005 0 180)
			(size 0 0)
			(layers "F.Cu" "F.Mask" "F.Paste")
			(net "P3V3_SSD9_PG_G1")
		)
		(pad "2" smd circle
			(at 0.40005 0 180)
			(size 0 0)
			(layers "F.Cu" "F.Mask" "F.Paste")
			(net "GND")
		)
	)
	(footprint ""
		(layer "F.Cu")
		(at 400.05762 -343.952322 90)
		(property "Reference" "C751"
			(at 0 0 90)
			(layer "F.SilkS")
			(hide yes)
			(effects
				(font
					(size 1.27 1.27)
				)
			)
		)
		(property "Value" ""
			(at 0 0 90)
			(layer "F.Fab")
			(effects
				(font
					(size 1.27 1.27)
				)
			)
		)
		(duplicate_pad_numbers_are_jumpers no)
		(fp_line
			(start 0.299974 -0.150114)
			(end 0.299974 0.150114)
			(stroke
				(width 0.1)
				(type default)
			)
			(layer "F.Fab")
		)
		(fp_line
			(start -0.299974 -0.150114)
			(end 0.299974 -0.150114)
			(stroke
				(width 0.1)
				(type default)
			)
			(layer "F.Fab")
		)
		(fp_line
			(start 0.299974 0.150114)
			(end -0.299974 0.150114)
			(stroke
				(width 0.1)
				(type default)
			)
			(layer "F.Fab")
		)
		(fp_line
			(start -0.299974 0.150114)
			(end -0.299974 -0.150114)
			(stroke
				(width 0.1)
				(type default)
			)
			(layer "F.Fab")
		)
		(pad "1" smd rect
			(at -0.2667 0 90)
			(size 0.3048 0.381)
			(layers "F.Cu" "F.Mask" "F.Paste")
			(net "P5E_PEX3_STN5_TX_DN<85>")
		)
		(pad "2" smd rect
			(at 0.2667 0 90)
			(size 0.3048 0.381)
			(layers "F.Cu" "F.Mask" "F.Paste")
			(net "P5E_PEX3_STN5_TX_C_DN<85>")
		)
	)
	(footprint ""
		(layer "F.Cu")
		(at 318.695324 -350.098614 90)
		(property "Reference" "C543"
			(at 0 0 90)
			(layer "F.SilkS")
			(hide yes)
			(effects
				(font
					(size 1.27 1.27)
				)
			)
		)
		(property "Value" ""
			(at 0 0 90)
			(layer "F.Fab")
			(effects
				(font
					(size 1.27 1.27)
				)
			)
		)
		(duplicate_pad_numbers_are_jumpers no)
		(fp_line
			(start 0.299974 -0.150114)
			(end 0.299974 0.150114)
			(stroke
				(width 0.1)
				(type default)
			)
			(layer "F.Fab")
		)
		(fp_line
			(start -0.299974 -0.150114)
			(end 0.299974 -0.150114)
			(stroke
				(width 0.1)
				(type default)
			)
			(layer "F.Fab")
		)
		(fp_line
			(start 0.299974 0.150114)
			(end -0.299974 0.150114)
			(stroke
				(width 0.1)
				(type default)
			)
			(layer "F.Fab")
		)
		(fp_line
			(start -0.299974 0.150114)
			(end -0.299974 -0.150114)
			(stroke
				(width 0.1)
				(type default)
			)
			(layer "F.Fab")
		)
		(pad "1" smd rect
			(at -0.2667 0 90)
			(size 0.3048 0.381)
			(layers "F.Cu" "F.Mask" "F.Paste")
			(net "P5E_PEX2_STN5_TX_DP<83>")
		)
		(pad "2" smd rect
			(at 0.2667 0 90)
			(size 0.3048 0.381)
			(layers "F.Cu" "F.Mask" "F.Paste")
			(net "P5E_PEX2_STN5_TX_C_DP<83>")
		)
	)
	(footprint ""
		(layer "F.Cu")
		(at 234.154472 -369.787424 90)
		(property "Reference" "PR40"
			(at 0 0 90)
			(layer "F.SilkS")
			(hide yes)
			(effects
				(font
					(size 1.27 1.27)
				)
			)
		)
		(property "Value" ""
			(at 0 0 90)
			(layer "F.Fab")
			(effects
				(font
					(size 1.27 1.27)
				)
			)
		)
		(duplicate_pad_numbers_are_jumpers no)
		(fp_line
			(start 0.7874 -0.4064)
			(end 0.7874 0.4064)
			(stroke
				(width 0.1524)
				(type default)
			)
			(layer "F.SilkS")
		)
		(fp_line
			(start -0.7874 -0.4064)
			(end 0.7874 -0.4064)
			(stroke
				(width 0.1524)
				(type default)
			)
			(layer "F.SilkS")
		)
		(fp_line
			(start 0.7874 0.4064)
			(end -0.7874 0.4064)
			(stroke
				(width 0.1524)
				(type default)
			)
			(layer "F.SilkS")
		)
		(fp_line
			(start -0.7874 0.4064)
			(end -0.7874 -0.4064)
			(stroke
				(width 0.1524)
				(type default)
			)
			(layer "F.SilkS")
		)
		(fp_line
			(start -0.12065 -0.305054)
			(end -0.12065 -0.2794)
			(stroke
				(width 0.1)
				(type default)
			)
			(layer "F.Fab")
		)
		(fp_line
			(start -0.67945 -0.305054)
			(end -0.12065 -0.305054)
			(stroke
				(width 0.1)
				(type default)
			)
			(layer "F.Fab")
		)
		(fp_line
			(start 0.67945 -0.3048)
			(end 0.67945 0.3048)
			(stroke
				(width 0.1)
				(type default)
			)
			(layer "F.Fab")
		)
		(fp_line
			(start 0.12065 -0.3048)
			(end 0.67945 -0.3048)
			(stroke
				(width 0.1)
				(type default)
			)
			(layer "F.Fab")
		)
		(fp_line
			(start 0.12065 -0.2794)
			(end 0.12065 -0.3048)
			(stroke
				(width 0.1)
				(type default)
			)
			(layer "F.Fab")
		)
		(fp_line
			(start -0.12065 -0.2794)
			(end 0.12065 -0.2794)
			(stroke
				(width 0.1)
				(type default)
			)
			(layer "F.Fab")
		)
		(fp_line
			(start 0.120396 0.2794)
			(end -0.12065 0.2794)
			(stroke
				(width 0.1)
				(type default)
			)
			(layer "F.Fab")
		)
		(fp_line
			(start -0.12065 0.2794)
			(end -0.12065 0.3048)
			(stroke
				(width 0.1)
				(type default)
			)
			(layer "F.Fab")
		)
		(fp_line
			(start 0.67945 0.3048)
			(end 0.120396 0.3048)
			(stroke
				(width 0.1)
				(type default)
			)
			(layer "F.Fab")
		)
		(fp_line
			(start 0.120396 0.3048)
			(end 0.120396 0.2794)
			(stroke
				(width 0.1)
				(type default)
			)
			(layer "F.Fab")
		)
		(fp_line
			(start -0.12065 0.3048)
			(end -0.67945 0.3048)
			(stroke
				(width 0.1)
				(type default)
			)
			(layer "F.Fab")
		)
		(fp_line
			(start -0.67945 0.3048)
			(end -0.67945 -0.305054)
			(stroke
				(width 0.1)
				(type default)
			)
			(layer "F.Fab")
		)
		(pad "1" smd circle
			(at -0.40005 0 90)
			(size 0 0)
			(layers "F.Cu" "F.Mask" "F.Paste")
			(net "HSC_FAULT_N_2")
		)
		(pad "2" smd circle
			(at 0.40005 0 90)
			(size 0 0)
			(layers "F.Cu" "F.Mask" "F.Paste")
			(net "HSC_FAULT_N")
		)
	)
	(footprint ""
		(layer "F.Cu")
		(at 169.293032 -350.098614 90)
		(property "Reference" "C2519"
			(at 0 0 90)
			(layer "F.SilkS")
			(hide yes)
			(effects
				(font
					(size 1.27 1.27)
				)
			)
		)
		(property "Value" ""
			(at 0 0 90)
			(layer "F.Fab")
			(effects
				(font
					(size 1.27 1.27)
				)
			)
		)
		(duplicate_pad_numbers_are_jumpers no)
		(fp_line
			(start 0.299974 -0.150114)
			(end 0.299974 0.150114)
			(stroke
				(width 0.1)
				(type default)
			)
			(layer "F.Fab")
		)
		(fp_line
			(start -0.299974 -0.150114)
			(end 0.299974 -0.150114)
			(stroke
				(width 0.1)
				(type default)
			)
			(layer "F.Fab")
		)
		(fp_line
			(start 0.299974 0.150114)
			(end -0.299974 0.150114)
			(stroke
				(width 0.1)
				(type default)
			)
			(layer "F.Fab")
		)
		(fp_line
			(start -0.299974 0.150114)
			(end -0.299974 -0.150114)
			(stroke
				(width 0.1)
				(type default)
			)
			(layer "F.Fab")
		)
		(pad "1" smd rect
			(at -0.2667 0 90)
			(size 0.3048 0.381)
			(layers "F.Cu" "F.Mask" "F.Paste")
			(net "P5E_PEX1_STN4_TX_DN<76>")
		)
		(pad "2" smd rect
			(at 0.2667 0 90)
			(size 0.3048 0.381)
			(layers "F.Cu" "F.Mask" "F.Paste")
			(net "P5E_PEX1_STN4_TX_C_DN<76>")
		)
	)
	(footprint ""
		(layer "F.Cu")
		(at 164.946076 -46.4439 180)
		(property "Reference" "U60"
			(at 0.100076 -2.45237 0)
			(unlocked yes)
			(layer "F.SilkS")
			(effects
				(font
					(size 0.7874 0.5842)
					(thickness 0.1524)
				)
			)
		)
		(property "Value" ""
			(at 0 0 180)
			(layer "F.Fab")
			(effects
				(font
					(size 1.27 1.27)
				)
			)
		)
		(duplicate_pad_numbers_are_jumpers no)
		(fp_line
			(start 1.500124 1.500124)
			(end 1.004062 1.500124)
			(stroke
				(width 0.1524)
				(type default)
			)
			(layer "F.SilkS")
		)
		(fp_line
			(start 1.500124 1.004062)
			(end 1.500124 1.500124)
			(stroke
				(width 0.1524)
				(type default)
			)
			(layer "F.SilkS")
		)
		(fp_line
			(start 1.500124 -1.500124)
			(end 1.500124 -1.004062)
			(stroke
				(width 0.1524)
				(type default)
			)
			(layer "F.SilkS")
		)
		(fp_line
			(start 1.004062 -1.500124)
			(end 1.500124 -1.500124)
			(stroke
				(width 0.1524)
				(type default)
			)
			(layer "F.SilkS")
		)
		(fp_line
			(start -1.004062 1.500124)
			(end -1.500124 1.500124)
			(stroke
				(width 0.1524)
				(type default)
			)
			(layer "F.SilkS")
		)
		(fp_line
			(start -1.500124 1.500124)
			(end -1.500124 1.004062)
			(stroke
				(width 0.1524)
				(type default)
			)
			(layer "F.SilkS")
		)
		(fp_line
			(start -1.500124 -1.004062)
			(end -1.500124 -1.500124)
			(stroke
				(width 0.1524)
				(type default)
			)
			(layer "F.SilkS")
		)
		(fp_line
			(start -1.500124 -1.500124)
			(end -1.004062 -1.500124)
			(stroke
				(width 0.1524)
				(type default)
			)
			(layer "F.SilkS")
		)
		(fp_poly
			(pts
				(xy -1.95834 -2.057146) (xy -2.676906 -1.338834) (xy -1.599184 -0.979678)
			)
			(stroke
				(width 0)
				(type default)
			)
			(fill yes)
			(layer "F.SilkS")
		)
		(fp_line
			(start 1.500124 1.500124)
			(end -1.500124 1.500124)
			(stroke
				(width 0.1)
				(type default)
			)
			(layer "F.Fab")
		)
		(fp_line
			(start 1.500124 -1.500124)
			(end 1.500124 1.500124)
			(stroke
				(width 0.1)
				(type default)
			)
			(layer "F.Fab")
		)
		(fp_line
			(start -1.500124 1.500124)
			(end -1.500124 -1.500124)
			(stroke
				(width 0.1)
				(type default)
			)
			(layer "F.Fab")
		)
		(fp_line
			(start -1.500124 -1.500124)
			(end 1.500124 -1.500124)
			(stroke
				(width 0.1)
				(type default)
			)
			(layer "F.Fab")
		)
		(fp_poly
			(pts
				(xy -2.847848 -1.258062) (xy -2.847848 -0.242062) (xy -1.831848 -0.750062)
			)
			(stroke
				(width 0)
				(type default)
			)
			(fill yes)
			(layer "F.Fab")
		)
		(pad "1" smd rect
			(at -1.400048 -0.750062 90)
			(size 0.2286 0.6096)
			(layers "F.Cu" "F.Mask" "F.Paste")
			(net "SSD5_ADC_A1")
		)
		(pad "2" smd rect
			(at -1.400048 -0.249936 90)
			(size 0.2286 0.6096)
			(layers "F.Cu" "F.Mask" "F.Paste")
			(net "SSD5_ADC_A0")
		)
		(pad "3" smd rect
			(at -1.400048 0.249936 90)
			(size 0.2286 0.6096)
			(layers "F.Cu" "F.Mask" "F.Paste")
			(net "SSD5_ADC_ALERT_N")
		)
		(pad "4" smd rect
			(at -1.400048 0.750062 90)
			(size 0.2286 0.6096)
			(layers "F.Cu" "F.Mask" "F.Paste")
			(net "SMB_SSD5_ADC_SDA")
		)
		(pad "5" smd rect
			(at -0.750062 1.400048 180)
			(size 0.2286 0.6096)
			(layers "F.Cu" "F.Mask" "F.Paste")
			(net "SMB_SSD5_ADC_SCL")
		)
		(pad "6" smd rect
			(at -0.249936 1.400048 180)
			(size 0.2286 0.6096)
			(layers "F.Cu" "F.Mask" "F.Paste")
			(net "Net_8732")
		)
		(pad "7" smd rect
			(at 0.249936 1.400048 180)
			(size 0.2286 0.6096)
			(layers "F.Cu" "F.Mask" "F.Paste")
			(net "Net_8731")
		)
		(pad "8" smd rect
			(at 0.750062 1.400048 180)
			(size 0.2286 0.6096)
			(layers "F.Cu" "F.Mask" "F.Paste")
			(net "Net_8730")
		)
		(pad "9" smd rect
			(at 1.400048 0.750062 90)
			(size 0.2286 0.6096)
			(layers "F.Cu" "F.Mask" "F.Paste")
			(net "P3V3_AUX")
		)
		(pad "10" smd rect
			(at 1.400048 0.249936 90)
			(size 0.2286 0.6096)
			(layers "F.Cu" "F.Mask" "F.Paste")
			(net "GND")
		)
		(pad "11" smd rect
			(at 1.400048 -0.249936 90)
			(size 0.2286 0.6096)
			(layers "F.Cu" "F.Mask" "F.Paste")
			(net "P12V_SSD5_R")
		)
		(pad "12" smd rect
			(at 1.400048 -0.750062 90)
			(size 0.2286 0.6096)
			(layers "F.Cu" "F.Mask" "F.Paste")
			(net "P12V_SSD5_VIN_N")
		)
		(pad "13" smd rect
			(at 0.750062 -1.400048 180)
			(size 0.2286 0.6096)
			(layers "F.Cu" "F.Mask" "F.Paste")
			(net "P12V_SSD5_VIN_P")
		)
		(pad "14" smd rect
			(at 0.249936 -1.400048 180)
			(size 0.2286 0.6096)
			(layers "F.Cu" "F.Mask" "F.Paste")
			(net "Net_8729")
		)
		(pad "15" smd rect
			(at -0.249936 -1.400048 180)
			(size 0.2286 0.6096)
			(layers "F.Cu" "F.Mask" "F.Paste")
			(net "Net_8728")
		)
		(pad "16" smd rect
			(at -0.750062 -1.400048 180)
			(size 0.2286 0.6096)
			(layers "F.Cu" "F.Mask" "F.Paste")
			(net "Net_8727")
		)
		(pad "TH" smd rect
			(at 0 0 180)
			(size 1.7018 1.7018)
			(layers "F.Cu" "F.Mask" "F.Paste")
			(net "GND")
		)
		(zone
			(layer "F.Cu")
			(hatch none 0.5)
			(connect_pads
				(clearance 0)
			)
			(min_thickness 0.25)
			(keepout
				(tracks not_allowed)
				(vias allowed)
				(pads allowed)
				(copperpour not_allowed)
				(footprints allowed)
			)
			(placement
				(enabled no)
				(sheetname "")
			)
			(fill
				(thermal_gap 0.5)
				(thermal_bridge_width 0.5)
				(island_removal_mode 0)
			)
			(polygon
				(pts
					(xy 165.990524 -46.4185) (xy 165.990524 -45.399452) (xy 163.901628 -45.399452) (xy 163.901628 -47.488348)
					(xy 165.990524 -47.488348) (xy 165.990524 -46.4439) (xy 165.847776 -46.4439) (xy 165.847776 -47.3456)
					(xy 164.044376 -47.3456) (xy 164.044376 -45.5422) (xy 165.847776 -45.5422) (xy 165.847776 -46.4185)
				)
			)
		)
	)
	(footprint ""
		(layer "F.Cu")
		(at 328.936604 -356.244906 90)
		(property "Reference" "C534"
			(at 0 0 90)
			(layer "F.SilkS")
			(hide yes)
			(effects
				(font
					(size 1.27 1.27)
				)
			)
		)
		(property "Value" ""
			(at 0 0 90)
			(layer "F.Fab")
			(effects
				(font
					(size 1.27 1.27)
				)
			)
		)
		(duplicate_pad_numbers_are_jumpers no)
		(fp_line
			(start 0.299974 -0.150114)
			(end 0.299974 0.150114)
			(stroke
				(width 0.1)
				(type default)
			)
			(layer "F.Fab")
		)
		(fp_line
			(start -0.299974 -0.150114)
			(end 0.299974 -0.150114)
			(stroke
				(width 0.1)
				(type default)
			)
			(layer "F.Fab")
		)
		(fp_line
			(start 0.299974 0.150114)
			(end -0.299974 0.150114)
			(stroke
				(width 0.1)
				(type default)
			)
			(layer "F.Fab")
		)
		(fp_line
			(start -0.299974 0.150114)
			(end -0.299974 -0.150114)
			(stroke
				(width 0.1)
				(type default)
			)
			(layer "F.Fab")
		)
		(pad "1" smd rect
			(at -0.2667 0 90)
			(size 0.3048 0.381)
			(layers "F.Cu" "F.Mask" "F.Paste")
			(net "P5E_PEX2_STN5_TX_DN<88>")
		)
		(pad "2" smd rect
			(at 0.2667 0 90)
			(size 0.3048 0.381)
			(layers "F.Cu" "F.Mask" "F.Paste")
			(net "P5E_PEX2_STN5_TX_C_DN<88>")
		)
	)
)
